# S9S_MB_2U (Grand Teton) — schematic netlist excerpt (pin names and nets, part order shuffled) for the footprints in the layout excerpt that follows; sources: Cadence DE-HDL packaged netlist, KiCad conversion of 03242023_DA0F0TMBIJ0_F0T_Motherboard_J_brd_V01_OCP.brd

C544  Q_CAP  0.1UF 25V 10% X7R  pkg 0402  page 133 : A = P3V3_AUX ; B = GND
R3636  Q_RES  0 5% CHIP  pkg 0402LF  page 206 : A = OCP_SFF_CLK_OE_N ; B = FM_DB2000_11_OE_N

(kicad_pcb
	(version 20260206)
	(generator "pcbnew")
	(generator_version "10.0")
	(general
		(thickness 1.6)
		(legacy_teardrops no)
	)
	(paper "A4")
	(title_block
		(title "03242023_DA0F0TMBIJ0_F0T_Motherboard_J_brd_V01_OCP.brd")
		(comment 1 "Grand Teton / footprints 4267-4268 of 6105")
	)
	(layers
		(0 "F.Cu" signal "TOP")
		(4 "In1.Cu" signal "GND")
		(6 "In2.Cu" signal "IN1")
		(8 "In3.Cu" signal "GND1")
		(10 "In4.Cu" signal "IN2")
		(12 "In5.Cu" signal "GND2")
		(14 "In6.Cu" signal "IN3")
		(16 "In7.Cu" signal "GND3")
		(18 "In8.Cu" signal "VCC")
		(20 "In9.Cu" signal "VCC1")
		(22 "In10.Cu" signal "GND4")
		(24 "In11.Cu" signal "IN4")
		(26 "In12.Cu" signal "GND5")
		(28 "In13.Cu" signal "IN5")
		(30 "In14.Cu" signal "GND6")
		(32 "In15.Cu" signal "IN6")
		(34 "In16.Cu" signal "GND7")
		(2 "B.Cu" signal "BOTTOM")
		(9 "F.Adhes" user "F.Adhesive")
		(11 "B.Adhes" user "B.Adhesive")
		(13 "F.Paste" user "Package Geometry/Pastemask Top")
		(15 "B.Paste" user "Package Geometry/Pastemask Bottom")
		(5 "F.SilkS" user "Ref Des/Silkscreen Top")
		(7 "B.SilkS" user "Ref Des/Silkscreen Bottom")
		(1 "F.Mask" user "Board Geometry/Soldermask Top")
		(3 "B.Mask" user "Board Geometry/Soldermask Bottom")
		(17 "Dwgs.User" user "User.Drawings")
		(19 "Cmts.User" user "User.Comments")
		(21 "Eco1.User" user "User.Eco1")
		(23 "Eco2.User" user "User.Eco2")
		(25 "Edge.Cuts" user "Board Geometry/Outline")
		(27 "Margin" user)
		(31 "F.CrtYd" user "Package Geometry/Place Bound Top")
		(29 "B.CrtYd" user "Package Geometry/Place Bound Bottom")
		(35 "F.Fab" user "Ref Des/Assembly Top")
		(33 "B.Fab" user "Ref Des/Assembly Bottom")
	)
	(footprint ""
		(layer "B.Cu")
		(at 213.841838 -195.58635)
		(property "Reference" "C544"
			(at 0 0 0)
			(layer "B.SilkS")
			(hide yes)
			(effects
				(font
					(size 1.27 1.27)
				)
				(justify mirror)
			)
		)
		(property "Value" ""
			(at 0 0 0)
			(layer "B.Fab")
			(effects
				(font
					(size 1.27 1.27)
				)
				(justify mirror)
			)
		)
		(duplicate_pad_numbers_are_jumpers no)
		(fp_line
			(start -0.7874 -0.4064)
			(end -0.7874 0.4064)
			(stroke
				(width 0.1524)
				(type default)
			)
			(layer "B.SilkS")
		)
		(fp_line
			(start -0.7874 0.4064)
			(end 0.7874 0.4064)
			(stroke
				(width 0.1524)
				(type default)
			)
			(layer "B.SilkS")
		)
		(fp_line
			(start 0.7874 -0.4064)
			(end -0.7874 -0.4064)
			(stroke
				(width 0.1524)
				(type default)
			)
			(layer "B.SilkS")
		)
		(fp_line
			(start 0.7874 0.4064)
			(end 0.7874 -0.4064)
			(stroke
				(width 0.1524)
				(type default)
			)
			(layer "B.SilkS")
		)
		(fp_line
			(start -0.67945 -0.3048)
			(end -0.67945 0.3048)
			(stroke
				(width 0.1)
				(type default)
			)
			(layer "B.Fab")
		)
		(fp_line
			(start -0.67945 0.3048)
			(end -0.120396 0.3048)
			(stroke
				(width 0.1)
				(type default)
			)
			(layer "B.Fab")
		)
		(fp_line
			(start -0.12065 -0.3048)
			(end -0.67945 -0.3048)
			(stroke
				(width 0.1)
				(type default)
			)
			(layer "B.Fab")
		)
		(fp_line
			(start -0.12065 -0.2794)
			(end -0.12065 -0.3048)
			(stroke
				(width 0.1)
				(type default)
			)
			(layer "B.Fab")
		)
		(fp_line
			(start -0.120396 0.2794)
			(end 0.12065 0.2794)
			(stroke
				(width 0.1)
				(type default)
			)
			(layer "B.Fab")
		)
		(fp_line
			(start -0.120396 0.3048)
			(end -0.120396 0.2794)
			(stroke
				(width 0.1)
				(type default)
			)
			(layer "B.Fab")
		)
		(fp_line
			(start 0.12065 -0.305054)
			(end 0.12065 -0.2794)
			(stroke
				(width 0.1)
				(type default)
			)
			(layer "B.Fab")
		)
		(fp_line
			(start 0.12065 -0.2794)
			(end -0.12065 -0.2794)
			(stroke
				(width 0.1)
				(type default)
			)
			(layer "B.Fab")
		)
		(fp_line
			(start 0.12065 0.2794)
			(end 0.12065 0.3048)
			(stroke
				(width 0.1)
				(type default)
			)
			(layer "B.Fab")
		)
		(fp_line
			(start 0.12065 0.3048)
			(end 0.67945 0.3048)
			(stroke
				(width 0.1)
				(type default)
			)
			(layer "B.Fab")
		)
		(fp_line
			(start 0.67945 -0.305054)
			(end 0.12065 -0.305054)
			(stroke
				(width 0.1)
				(type default)
			)
			(layer "B.Fab")
		)
		(fp_line
			(start 0.67945 0.3048)
			(end 0.67945 -0.305054)
			(stroke
				(width 0.1)
				(type default)
			)
			(layer "B.Fab")
		)
		(pad "1" smd circle
			(at 0.40005 0 180)
			(size 0 0)
			(layers "B.Cu" "B.Mask" "B.Paste")
			(net "P3V3_AUX")
		)
		(pad "2" smd circle
			(at -0.40005 0 180)
			(size 0 0)
			(layers "B.Cu" "B.Mask" "B.Paste")
			(net "GND")
		)
	)
	(footprint ""
		(layer "B.Cu")
		(at 230.48468 -118.760748 -90)
		(property "Reference" "R3636"
			(at 0 0 90)
			(layer "B.SilkS")
			(hide yes)
			(effects
				(font
					(size 1.27 1.27)
				)
				(justify mirror)
			)
		)
		(property "Value" ""
			(at 0 0 90)
			(layer "B.Fab")
			(effects
				(font
					(size 1.27 1.27)
				)
				(justify mirror)
			)
		)
		(duplicate_pad_numbers_are_jumpers no)
		(fp_line
			(start -0.7874 0.4064)
			(end 0.7874 0.4064)
			(stroke
				(width 0.1524)
				(type default)
			)
			(layer "B.SilkS")
		)
		(fp_line
			(start 0.7874 0.4064)
			(end 0.7874 -0.4064)
			(stroke
				(width 0.1524)
				(type default)
			)
			(layer "B.SilkS")
		)
		(fp_line
			(start -0.7874 -0.4064)
			(end -0.7874 0.4064)
			(stroke
				(width 0.1524)
				(type default)
			)
			(layer "B.SilkS")
		)
		(fp_line
			(start 0.7874 -0.4064)
			(end -0.7874 -0.4064)
			(stroke
				(width 0.1524)
				(type default)
			)
			(layer "B.SilkS")
		)
		(fp_line
			(start -0.67945 0.3048)
			(end -0.120396 0.3048)
			(stroke
				(width 0.1)
				(type default)
			)
			(layer "B.Fab")
		)
		(fp_line
			(start -0.120396 0.3048)
			(end -0.120396 0.2794)
			(stroke
				(width 0.1)
				(type default)
			)
			(layer "B.Fab")
		)
		(fp_line
			(start 0.12065 0.3048)
			(end 0.67945 0.3048)
			(stroke
				(width 0.1)
				(type default)
			)
			(layer "B.Fab")
		)
		(fp_line
			(start 0.67945 0.3048)
			(end 0.67945 -0.305054)
			(stroke
				(width 0.1)
				(type default)
			)
			(layer "B.Fab")
		)
		(fp_line
			(start -0.120396 0.2794)
			(end 0.12065 0.2794)
			(stroke
				(width 0.1)
				(type default)
			)
			(layer "B.Fab")
		)
		(fp_line
			(start 0.12065 0.2794)
			(end 0.12065 0.3048)
			(stroke
				(width 0.1)
				(type default)
			)
			(layer "B.Fab")
		)
		(fp_line
			(start -0.12065 -0.2794)
			(end -0.12065 -0.3048)
			(stroke
				(width 0.1)
				(type default)
			)
			(layer "B.Fab")
		)
		(fp_line
			(start 0.12065 -0.2794)
			(end -0.12065 -0.2794)
			(stroke
				(width 0.1)
				(type default)
			)
			(layer "B.Fab")
		)
		(fp_line
			(start -0.67945 -0.3048)
			(end -0.67945 0.3048)
			(stroke
				(width 0.1)
				(type default)
			)
			(layer "B.Fab")
		)
		(fp_line
			(start -0.12065 -0.3048)
			(end -0.67945 -0.3048)
			(stroke
				(width 0.1)
				(type default)
			)
			(layer "B.Fab")
		)
		(fp_line
			(start 0.12065 -0.305054)
			(end 0.12065 -0.2794)
			(stroke
				(width 0.1)
				(type default)
			)
			(layer "B.Fab")
		)
		(fp_line
			(start 0.67945 -0.305054)
			(end 0.12065 -0.305054)
			(stroke
				(width 0.1)
				(type default)
			)
			(layer "B.Fab")
		)
		(pad "1" smd circle
			(at 0.40005 0 90)
			(size 0 0)
			(layers "B.Cu" "B.Mask" "B.Paste")
			(net "OCP_SFF_CLK_OE_N")
		)
		(pad "2" smd circle
			(at -0.40005 0 90)
			(size 0 0)
			(layers "B.Cu" "B.Mask" "B.Paste")
			(net "FM_DB2000_11_OE_N")
		)
	)
)
